# S9S_MB_2U (Grand Teton) — schematic netlist excerpt (pin names and nets, part order shuffled) for the footprints in the layout excerpt that follows; sources: Cadence DE-HDL packaged netlist, KiCad conversion of 03242023_DA0F0TMBIJ0_F0T_Motherboard_J_brd_V01_OCP.brd

PR4522  Q_RES  10M 1% EMPTY  pkg 0402LF  page 162 : A = P12V_OCP_V3_2 ; B = P12V_OCP_GATE_2
C1518  Q_CAP_DIFFBUS  DIFF BUS_0.22UF 6.3V 20% X6S  pkg C0201  page 177 : \1\ = P5E_CPU1_PE3_TX_C_DN<14> ; \2\ = P5E_CPU1_PE3_TX_DN<14>
PC1287  Q_CAP  22UF 4V 20% X6S  pkg C0805  page 300 : A = PVNN_MAIN_CPU1 ; B = GND

(kicad_pcb
	(version 20260206)
	(generator "pcbnew")
	(generator_version "10.0")
	(general
		(thickness 1.6)
		(legacy_teardrops no)
	)
	(paper "A4")
	(title_block
		(title "03242023_DA0F0TMBIJ0_F0T_Motherboard_J_brd_V01_OCP.brd")
		(comment 1 "Grand Teton / footprints 387-389 of 6105")
	)
	(layers
		(0 "F.Cu" signal "TOP")
		(4 "In1.Cu" signal "GND")
		(6 "In2.Cu" signal "IN1")
		(8 "In3.Cu" signal "GND1")
		(10 "In4.Cu" signal "IN2")
		(12 "In5.Cu" signal "GND2")
		(14 "In6.Cu" signal "IN3")
		(16 "In7.Cu" signal "GND3")
		(18 "In8.Cu" signal "VCC")
		(20 "In9.Cu" signal "VCC1")
		(22 "In10.Cu" signal "GND4")
		(24 "In11.Cu" signal "IN4")
		(26 "In12.Cu" signal "GND5")
		(28 "In13.Cu" signal "IN5")
		(30 "In14.Cu" signal "GND6")
		(32 "In15.Cu" signal "IN6")
		(34 "In16.Cu" signal "GND7")
		(2 "B.Cu" signal "BOTTOM")
		(9 "F.Adhes" user "F.Adhesive")
		(11 "B.Adhes" user "B.Adhesive")
		(13 "F.Paste" user "Package Geometry/Pastemask Top")
		(15 "B.Paste" user "Package Geometry/Pastemask Bottom")
		(5 "F.SilkS" user "Ref Des/Silkscreen Top")
		(7 "B.SilkS" user "Ref Des/Silkscreen Bottom")
		(1 "F.Mask" user "Board Geometry/Soldermask Top")
		(3 "B.Mask" user "Board Geometry/Soldermask Bottom")
		(17 "Dwgs.User" user "User.Drawings")
		(19 "Cmts.User" user "User.Comments")
		(21 "Eco1.User" user "User.Eco1")
		(23 "Eco2.User" user "User.Eco2")
		(25 "Edge.Cuts" user "Board Geometry/Outline")
		(27 "Margin" user)
		(31 "F.CrtYd" user "Package Geometry/Place Bound Top")
		(29 "B.CrtYd" user "Package Geometry/Place Bound Bottom")
		(35 "F.Fab" user "Ref Des/Assembly Top")
		(33 "B.Fab" user "Ref Des/Assembly Bottom")
	)
	(footprint ""
		(layer "F.Cu")
		(at 80.925162 -25.358598 180)
		(property "Reference" "PR4522"
			(at 0 0 180)
			(layer "F.SilkS")
			(hide yes)
			(effects
				(font
					(size 1.27 1.27)
				)
			)
		)
		(property "Value" ""
			(at 0 0 180)
			(layer "F.Fab")
			(effects
				(font
					(size 1.27 1.27)
				)
			)
		)
		(duplicate_pad_numbers_are_jumpers no)
		(fp_line
			(start 0.7874 0.4064)
			(end -0.7874 0.4064)
			(stroke
				(width 0.1524)
				(type default)
			)
			(layer "F.SilkS")
		)
		(fp_line
			(start 0.7874 -0.4064)
			(end 0.7874 0.4064)
			(stroke
				(width 0.1524)
				(type default)
			)
			(layer "F.SilkS")
		)
		(fp_line
			(start -0.7874 0.4064)
			(end -0.7874 -0.4064)
			(stroke
				(width 0.1524)
				(type default)
			)
			(layer "F.SilkS")
		)
		(fp_line
			(start -0.7874 -0.4064)
			(end 0.7874 -0.4064)
			(stroke
				(width 0.1524)
				(type default)
			)
			(layer "F.SilkS")
		)
		(fp_line
			(start 0.67945 0.3048)
			(end 0.120396 0.3048)
			(stroke
				(width 0.1)
				(type default)
			)
			(layer "F.Fab")
		)
		(fp_line
			(start 0.67945 -0.3048)
			(end 0.67945 0.3048)
			(stroke
				(width 0.1)
				(type default)
			)
			(layer "F.Fab")
		)
		(fp_line
			(start 0.12065 -0.2794)
			(end 0.12065 -0.3048)
			(stroke
				(width 0.1)
				(type default)
			)
			(layer "F.Fab")
		)
		(fp_line
			(start 0.12065 -0.3048)
			(end 0.67945 -0.3048)
			(stroke
				(width 0.1)
				(type default)
			)
			(layer "F.Fab")
		)
		(fp_line
			(start 0.120396 0.3048)
			(end 0.120396 0.2794)
			(stroke
				(width 0.1)
				(type default)
			)
			(layer "F.Fab")
		)
		(fp_line
			(start 0.120396 0.2794)
			(end -0.12065 0.2794)
			(stroke
				(width 0.1)
				(type default)
			)
			(layer "F.Fab")
		)
		(fp_line
			(start -0.12065 0.3048)
			(end -0.67945 0.3048)
			(stroke
				(width 0.1)
				(type default)
			)
			(layer "F.Fab")
		)
		(fp_line
			(start -0.12065 0.2794)
			(end -0.12065 0.3048)
			(stroke
				(width 0.1)
				(type default)
			)
			(layer "F.Fab")
		)
		(fp_line
			(start -0.12065 -0.2794)
			(end 0.12065 -0.2794)
			(stroke
				(width 0.1)
				(type default)
			)
			(layer "F.Fab")
		)
		(fp_line
			(start -0.12065 -0.305054)
			(end -0.12065 -0.2794)
			(stroke
				(width 0.1)
				(type default)
			)
			(layer "F.Fab")
		)
		(fp_line
			(start -0.67945 0.3048)
			(end -0.67945 -0.305054)
			(stroke
				(width 0.1)
				(type default)
			)
			(layer "F.Fab")
		)
		(fp_line
			(start -0.67945 -0.305054)
			(end -0.12065 -0.305054)
			(stroke
				(width 0.1)
				(type default)
			)
			(layer "F.Fab")
		)
		(pad "1" smd circle
			(at -0.40005 0 180)
			(size 0 0)
			(layers "F.Cu" "F.Mask" "F.Paste")
			(net "P12V_OCP_V3_2")
		)
		(pad "2" smd circle
			(at 0.40005 0 180)
			(size 0 0)
			(layers "F.Cu" "F.Mask" "F.Paste")
			(net "P12V_OCP_GATE_2")
		)
	)
	(footprint ""
		(layer "F.Cu")
		(at 124.538994 -408.517344 -90)
		(property "Reference" "C1518"
			(at 0 0 270)
			(layer "F.SilkS")
			(hide yes)
			(effects
				(font
					(size 1.27 1.27)
				)
			)
		)
		(property "Value" ""
			(at 0 0 270)
			(layer "F.Fab")
			(effects
				(font
					(size 1.27 1.27)
				)
			)
		)
		(duplicate_pad_numbers_are_jumpers no)
		(fp_line
			(start -0.299974 0.150114)
			(end -0.299974 -0.150114)
			(stroke
				(width 0.1)
				(type default)
			)
			(layer "F.Fab")
		)
		(fp_line
			(start 0.299974 0.150114)
			(end -0.299974 0.150114)
			(stroke
				(width 0.1)
				(type default)
			)
			(layer "F.Fab")
		)
		(fp_line
			(start -0.299974 -0.150114)
			(end 0.299974 -0.150114)
			(stroke
				(width 0.1)
				(type default)
			)
			(layer "F.Fab")
		)
		(fp_line
			(start 0.299974 -0.150114)
			(end 0.299974 0.150114)
			(stroke
				(width 0.1)
				(type default)
			)
			(layer "F.Fab")
		)
		(pad "1" smd rect
			(at -0.2667 0 270)
			(size 0.3048 0.381)
			(layers "F.Cu" "F.Mask" "F.Paste")
			(net "P5E_CPU1_PE3_TX_C_DN<14>")
		)
		(pad "2" smd rect
			(at 0.2667 0 270)
			(size 0.3048 0.381)
			(layers "F.Cu" "F.Mask" "F.Paste")
			(net "P5E_CPU1_PE3_TX_DN<14>")
		)
	)
	(footprint ""
		(layer "F.Cu")
		(at 36.789106 -178.52009)
		(property "Reference" "PC1287"
			(at 0 0 0)
			(layer "F.SilkS")
			(hide yes)
			(effects
				(font
					(size 1.27 1.27)
				)
			)
		)
		(property "Value" ""
			(at 0 0 0)
			(layer "F.Fab")
			(effects
				(font
					(size 1.27 1.27)
				)
			)
		)
		(duplicate_pad_numbers_are_jumpers no)
		(fp_line
			(start -1.524 -0.762)
			(end 1.524 -0.762)
			(stroke
				(width 0.1524)
				(type default)
			)
			(layer "F.SilkS")
		)
		(fp_line
			(start -1.524 0.762)
			(end -1.524 -0.762)
			(stroke
				(width 0.1524)
				(type default)
			)
			(layer "F.SilkS")
		)
		(fp_line
			(start 1.524 -0.762)
			(end 1.524 0.762)
			(stroke
				(width 0.1524)
				(type default)
			)
			(layer "F.SilkS")
		)
		(fp_line
			(start 1.524 0.762)
			(end -1.524 0.762)
			(stroke
				(width 0.1524)
				(type default)
			)
			(layer "F.SilkS")
		)
		(fp_line
			(start -1.1049 -0.724916)
			(end -1.1049 0.724916)
			(stroke
				(width 0.1)
				(type default)
			)
			(layer "F.Fab")
		)
		(fp_line
			(start -1.1049 0.724916)
			(end 1.1049 0.724916)
			(stroke
				(width 0.1)
				(type default)
			)
			(layer "F.Fab")
		)
		(fp_line
			(start 1.1049 -0.724916)
			(end -1.1049 -0.724916)
			(stroke
				(width 0.1)
				(type default)
			)
			(layer "F.Fab")
		)
		(fp_line
			(start 1.1049 0.724916)
			(end 1.1049 -0.724916)
			(stroke
				(width 0.1)
				(type default)
			)
			(layer "F.Fab")
		)
		(pad "1" smd rect
			(at -0.889 0 180)
			(size 1.016 1.27)
			(layers "F.Cu" "F.Mask" "F.Paste")
			(net "PVNN_MAIN_CPU1")
		)
		(pad "2" smd rect
			(at 0.889 0 180)
			(size 1.016 1.27)
			(layers "F.Cu" "F.Mask" "F.Paste")
			(net "GND")
		)
	)
)
